(kicad_pcb
	(version 20260206)
	(generator "pcbnew")
	(generator_version "10.0")
	(general
		(thickness 1.6)
		(legacy_teardrops no)
	)
	(paper "A4")
	(title_block
		(title "baseboard — 13948-1b.1110WZS1818.brd")
		(comment 1 "Honey Badger (Wiwynn) / footprints 1488-1494 of 2523")
	)
	(layers
		(0 "F.Cu" signal "TOP")
		(4 "In1.Cu" signal "L2GND")
		(6 "In2.Cu" signal "L3")
		(8 "In3.Cu" signal "L4VCC")
		(10 "In4.Cu" signal "L5VCC")
		(12 "In5.Cu" signal "L6")
		(14 "In6.Cu" signal "L7GND")
		(2 "B.Cu" signal "BOTTOM")
		(9 "F.Adhes" user "F.Adhesive")
		(11 "B.Adhes" user "B.Adhesive")
		(13 "F.Paste" user "Package Geometry/Pastemask Top")
		(15 "B.Paste" user "Package Geometry/Pastemask Bottom")
		(5 "F.SilkS" user "Ref Des/Silkscreen Top")
		(7 "B.SilkS" user "Ref Des/Silkscreen Bottom")
		(1 "F.Mask" user "Board Geometry/Soldermask Top")
		(3 "B.Mask" user "Board Geometry/Soldermask Bottom")
		(17 "Dwgs.User" user "User.Drawings")
		(19 "Cmts.User" user "User.Comments")
		(21 "Eco1.User" user "User.Eco1")
		(23 "Eco2.User" user "User.Eco2")
		(25 "Edge.Cuts" user "Board Geometry/Outline")
		(27 "Margin" user)
		(31 "F.CrtYd" user "Package Geometry/Place Bound Top")
		(29 "B.CrtYd" user "Package Geometry/Place Bound Bottom")
		(35 "F.Fab" user "Ref Des/Assembly Top")
		(33 "B.Fab" user "Ref Des/Assembly Bottom")
	)
	(footprint ""
		(layer "F.Cu")
		(at 18.873216 -213.79688 180)
		(property "Reference" "SR305"
			(at 0 0 180)
			(layer "F.SilkS")
			(hide yes)
			(effects
				(font
					(size 1.27 1.27)
				)
			)
		)
		(property "Value" "0R2J-2-GP"
			(at 0.064008 -3.993896 180)
			(unlocked yes)
			(layer "F.Fab")
			(hide yes)
			(effects
				(font
					(size 1.016 1.016)
					(thickness 0.1524)
				)
			)
		)
		(property "Device Type" "R402H16"
			(at 0.064008 -5.517896 180)
			(unlocked yes)
			(layer "F.Fab")
			(hide yes)
			(effects
				(font
					(size 1.016 1.016)
					(thickness 0.1524)
				)
			)
		)
		(duplicate_pad_numbers_are_jumpers no)
		(fp_line
			(start 0.508 -0.9398)
			(end -0.508 -0.9398)
			(stroke
				(width 0.1524)
				(type default)
			)
			(layer "F.SilkS")
		)
		(fp_line
			(start -0.508 -0.9398)
			(end -0.508 0.9398)
			(stroke
				(width 0.1524)
				(type default)
			)
			(layer "F.SilkS")
		)
		(fp_rect
			(start -0.508 0.9398)
			(end 0.508 -0.9398)
			(stroke
				(width 0)
				(type default)
			)
			(fill no)
			(layer "F.CrtYd")
		)
		(fp_rect
			(start -0.508 0.9398)
			(end 0.508 -0.9398)
			(stroke
				(width 0)
				(type default)
			)
			(fill no)
			(layer "F.Fab")
		)
		(pad "1" smd custom
			(at 0 -0.4445 180)
			(size 0.1397 0.1397)
			(layers "F.Cu" "F.Mask" "F.Paste")
			(net "I2C_IO_EXP_RESET#")
			(options
				(clearance outline)
				(anchor circle)
			)
			(primitives
				(gr_poly
					(pts
						(arc
							(start -0.1778 -0.2794)
							(mid -0.249642 -0.249642)
							(end -0.2794 -0.1778)
						)
						(arc
							(start -0.2794 0.1778)
							(mid -0.249642 0.249642)
							(end -0.1778 0.2794)
						)
						(arc
							(start 0.1778 0.2794)
							(mid 0.249642 0.249642)
							(end 0.2794 0.1778)
						)
						(arc
							(start 0.2794 -0.1778)
							(mid 0.249642 -0.249642)
							(end 0.1778 -0.2794)
						)
					)
					(width 0)
					(fill yes)
				)
			)
		)
		(pad "2" smd custom
			(at 0 0.4445 180)
			(size 0.1397 0.1397)
			(layers "F.Cu" "F.Mask" "F.Paste")
			(net "I2C_IO_EXP_RESET#_PWR")
			(options
				(clearance outline)
				(anchor circle)
			)
			(primitives
				(gr_poly
					(pts
						(arc
							(start -0.1778 -0.2794)
							(mid -0.249642 -0.249642)
							(end -0.2794 -0.1778)
						)
						(arc
							(start -0.2794 0.1778)
							(mid -0.249642 0.249642)
							(end -0.1778 0.2794)
						)
						(arc
							(start 0.1778 0.2794)
							(mid 0.249642 0.249642)
							(end 0.2794 0.1778)
						)
						(arc
							(start 0.2794 -0.1778)
							(mid 0.249642 -0.249642)
							(end 0.1778 -0.2794)
						)
					)
					(width 0)
					(fill yes)
				)
			)
		)
	)
	(footprint ""
		(layer "F.Cu")
		(at 333.883 -10.541)
		(property "Reference" "R86"
			(at 0 0 0)
			(layer "F.SilkS")
			(hide yes)
			(effects
				(font
					(size 1.27 1.27)
				)
			)
		)
		(property "Value" "150R2F-1-GP"
			(at 0.064008 -3.993896 0)
			(unlocked yes)
			(layer "F.Fab")
			(hide yes)
			(effects
				(font
					(size 1.016 1.016)
					(thickness 0.1524)
				)
			)
		)
		(property "Device Type" "R402H16"
			(at 0.064008 -5.517896 0)
			(unlocked yes)
			(layer "F.Fab")
			(hide yes)
			(effects
				(font
					(size 1.016 1.016)
					(thickness 0.1524)
				)
			)
		)
		(duplicate_pad_numbers_are_jumpers no)
		(fp_line
			(start -0.508 -0.9398)
			(end -0.508 0.9398)
			(stroke
				(width 0.1524)
				(type default)
			)
			(layer "F.SilkS")
		)
		(fp_line
			(start 0.508 -0.9398)
			(end -0.508 -0.9398)
			(stroke
				(width 0.1524)
				(type default)
			)
			(layer "F.SilkS")
		)
		(fp_rect
			(start -0.508 0.9398)
			(end 0.508 -0.9398)
			(stroke
				(width 0)
				(type default)
			)
			(fill no)
			(layer "F.CrtYd")
		)
		(fp_rect
			(start -0.508 0.9398)
			(end 0.508 -0.9398)
			(stroke
				(width 0)
				(type default)
			)
			(fill no)
			(layer "F.Fab")
		)
		(pad "1" smd custom
			(at 0 -0.4445)
			(size 0.1397 0.1397)
			(layers "F.Cu" "F.Mask" "F.Paste")
			(net "P3V3_STBY")
			(options
				(clearance outline)
				(anchor circle)
			)
			(primitives
				(gr_poly
					(pts
						(arc
							(start -0.1778 -0.2794)
							(mid -0.249642 -0.249642)
							(end -0.2794 -0.1778)
						)
						(arc
							(start -0.2794 0.1778)
							(mid -0.249642 0.249642)
							(end -0.1778 0.2794)
						)
						(arc
							(start 0.1778 0.2794)
							(mid 0.249642 0.249642)
							(end 0.2794 0.1778)
						)
						(arc
							(start 0.2794 -0.1778)
							(mid 0.249642 -0.249642)
							(end 0.1778 -0.2794)
						)
					)
					(width 0)
					(fill yes)
				)
			)
		)
		(pad "2" smd custom
			(at 0 0.4445)
			(size 0.1397 0.1397)
			(layers "F.Cu" "F.Mask" "F.Paste")
			(net "CONSOLE_LED_1")
			(options
				(clearance outline)
				(anchor circle)
			)
			(primitives
				(gr_poly
					(pts
						(arc
							(start -0.1778 -0.2794)
							(mid -0.249642 -0.249642)
							(end -0.2794 -0.1778)
						)
						(arc
							(start -0.2794 0.1778)
							(mid -0.249642 0.249642)
							(end -0.1778 0.2794)
						)
						(arc
							(start 0.1778 0.2794)
							(mid 0.249642 0.249642)
							(end 0.2794 0.1778)
						)
						(arc
							(start 0.2794 -0.1778)
							(mid 0.249642 -0.249642)
							(end 0.1778 -0.2794)
						)
					)
					(width 0)
					(fill yes)
				)
			)
		)
	)
	(footprint ""
		(layer "F.Cu")
		(at 90.683842 -121.483882 90)
		(property "Reference" "SR753"
			(at 0 0 90)
			(layer "F.SilkS")
			(hide yes)
			(effects
				(font
					(size 1.27 1.27)
				)
			)
		)
		(property "Value" "4K7R2F-GP"
			(at 0.064008 -3.993896 90)
			(unlocked yes)
			(layer "F.Fab")
			(hide yes)
			(effects
				(font
					(size 1.016 1.016)
					(thickness 0.1524)
				)
			)
		)
		(property "Device Type" "R402H16"
			(at 0.064008 -5.517896 90)
			(unlocked yes)
			(layer "F.Fab")
			(hide yes)
			(effects
				(font
					(size 1.016 1.016)
					(thickness 0.1524)
				)
			)
		)
		(duplicate_pad_numbers_are_jumpers no)
		(fp_line
			(start 0.508 -0.9398)
			(end -0.508 -0.9398)
			(stroke
				(width 0.1524)
				(type default)
			)
			(layer "F.SilkS")
		)
		(fp_line
			(start -0.508 -0.9398)
			(end -0.508 0.9398)
			(stroke
				(width 0.1524)
				(type default)
			)
			(layer "F.SilkS")
		)
		(fp_rect
			(start -0.508 0.9398)
			(end 0.508 -0.9398)
			(stroke
				(width 0)
				(type default)
			)
			(fill no)
			(layer "F.CrtYd")
		)
		(fp_rect
			(start -0.508 0.9398)
			(end 0.508 -0.9398)
			(stroke
				(width 0)
				(type default)
			)
			(fill no)
			(layer "F.Fab")
		)
		(pad "1" smd custom
			(at 0 -0.4445 90)
			(size 0.1397 0.1397)
			(layers "F.Cu" "F.Mask" "F.Paste")
			(net "BMC_I2C_F_SCL")
			(options
				(clearance outline)
				(anchor circle)
			)
			(primitives
				(gr_poly
					(pts
						(arc
							(start -0.1778 -0.2794)
							(mid -0.249642 -0.249642)
							(end -0.2794 -0.1778)
						)
						(arc
							(start -0.2794 0.1778)
							(mid -0.249642 0.249642)
							(end -0.1778 0.2794)
						)
						(arc
							(start 0.1778 0.2794)
							(mid 0.249642 0.249642)
							(end 0.2794 0.1778)
						)
						(arc
							(start 0.2794 -0.1778)
							(mid 0.249642 -0.249642)
							(end 0.1778 -0.2794)
						)
					)
					(width 0)
					(fill yes)
				)
			)
		)
		(pad "2" smd custom
			(at 0 0.4445 90)
			(size 0.1397 0.1397)
			(layers "F.Cu" "F.Mask" "F.Paste")
			(net "P3V3_STBY")
			(options
				(clearance outline)
				(anchor circle)
			)
			(primitives
				(gr_poly
					(pts
						(arc
							(start -0.1778 -0.2794)
							(mid -0.249642 -0.249642)
							(end -0.2794 -0.1778)
						)
						(arc
							(start -0.2794 0.1778)
							(mid -0.249642 0.249642)
							(end -0.1778 0.2794)
						)
						(arc
							(start 0.1778 0.2794)
							(mid 0.249642 0.249642)
							(end 0.2794 0.1778)
						)
						(arc
							(start 0.2794 -0.1778)
							(mid 0.249642 -0.249642)
							(end 0.1778 -0.2794)
						)
					)
					(width 0)
					(fill yes)
				)
			)
		)
	)
	(footprint ""
		(layer "F.Cu")
		(at 195.706492 -180.226716)
		(property "Reference" "R482"
			(at 0 0 0)
			(layer "F.SilkS")
			(hide yes)
			(effects
				(font
					(size 1.27 1.27)
				)
			)
		)
		(property "Value" "0R2J-2-GP"
			(at 0.064008 -3.993896 0)
			(unlocked yes)
			(layer "F.Fab")
			(hide yes)
			(effects
				(font
					(size 1.016 1.016)
					(thickness 0.1524)
				)
			)
		)
		(property "Device Type" "R402H16"
			(at 0.064008 -5.517896 0)
			(unlocked yes)
			(layer "F.Fab")
			(hide yes)
			(effects
				(font
					(size 1.016 1.016)
					(thickness 0.1524)
				)
			)
		)
		(duplicate_pad_numbers_are_jumpers no)
		(fp_line
			(start -0.508 -0.9398)
			(end -0.508 0.9398)
			(stroke
				(width 0.1524)
				(type default)
			)
			(layer "F.SilkS")
		)
		(fp_line
			(start 0.508 -0.9398)
			(end -0.508 -0.9398)
			(stroke
				(width 0.1524)
				(type default)
			)
			(layer "F.SilkS")
		)
		(fp_rect
			(start -0.508 0.9398)
			(end 0.508 -0.9398)
			(stroke
				(width 0)
				(type default)
			)
			(fill no)
			(layer "F.CrtYd")
		)
		(fp_rect
			(start -0.508 0.9398)
			(end 0.508 -0.9398)
			(stroke
				(width 0)
				(type default)
			)
			(fill no)
			(layer "F.Fab")
		)
		(pad "1" smd custom
			(at 0 -0.4445)
			(size 0.1397 0.1397)
			(layers "F.Cu" "F.Mask" "F.Paste")
			(net "HB_A_OUT")
			(options
				(clearance outline)
				(anchor circle)
			)
			(primitives
				(gr_poly
					(pts
						(arc
							(start -0.1778 -0.2794)
							(mid -0.249642 -0.249642)
							(end -0.2794 -0.1778)
						)
						(arc
							(start -0.2794 0.1778)
							(mid -0.249642 0.249642)
							(end -0.1778 0.2794)
						)
						(arc
							(start 0.1778 0.2794)
							(mid 0.249642 0.249642)
							(end 0.2794 0.1778)
						)
						(arc
							(start 0.2794 -0.1778)
							(mid 0.249642 -0.249642)
							(end 0.1778 -0.2794)
						)
					)
					(width 0)
					(fill yes)
				)
			)
		)
		(pad "2" smd custom
			(at 0 0.4445)
			(size 0.1397 0.1397)
			(layers "F.Cu" "F.Mask" "F.Paste")
			(net "INVERTER_G1")
			(options
				(clearance outline)
				(anchor circle)
			)
			(primitives
				(gr_poly
					(pts
						(arc
							(start -0.1778 -0.2794)
							(mid -0.249642 -0.249642)
							(end -0.2794 -0.1778)
						)
						(arc
							(start -0.2794 0.1778)
							(mid -0.249642 0.249642)
							(end -0.1778 0.2794)
						)
						(arc
							(start 0.1778 0.2794)
							(mid 0.249642 0.249642)
							(end 0.2794 0.1778)
						)
						(arc
							(start 0.2794 -0.1778)
							(mid 0.249642 -0.249642)
							(end 0.1778 -0.2794)
						)
					)
					(width 0)
					(fill yes)
				)
			)
		)
	)
	(footprint ""
		(layer "F.Cu")
		(at 297.163236 -154.221688 90)
		(property "Reference" "U21"
			(at 0 0 90)
			(layer "F.SilkS")
			(hide yes)
			(effects
				(font
					(size 1.27 1.27)
				)
			)
		)
		(property "Value" "ICS551MLFT-GP"
			(at -3.707384 -1.5367 90)
			(unlocked yes)
			(layer "F.Fab")
			(hide yes)
			(effects
				(font
					(size 1.016 1.016)
					(thickness 0.1524)
				)
			)
		)
		(property "Device Type" "SOIC8H69"
			(at -3.707384 -3.0607 90)
			(unlocked yes)
			(layer "F.Fab")
			(hide yes)
			(effects
				(font
					(size 1.016 1.016)
					(thickness 0.1524)
				)
			)
		)
		(duplicate_pad_numbers_are_jumpers no)
		(fp_line
			(start 2.1336 -1.4224)
			(end -2.7432 -1.4224)
			(stroke
				(width 0.1524)
				(type default)
			)
			(layer "F.SilkS")
		)
		(fp_line
			(start -2.7432 -1.4224)
			(end -2.7432 1.4224)
			(stroke
				(width 0.1524)
				(type default)
			)
			(layer "F.SilkS")
		)
		(fp_line
			(start -2.7178 -0.508)
			(end -2.1844 -0.0508)
			(stroke
				(width 0.1524)
				(type default)
			)
			(layer "F.SilkS")
		)
		(fp_line
			(start -2.1844 -0.0508)
			(end -2.7178 0.508)
			(stroke
				(width 0.1524)
				(type default)
			)
			(layer "F.SilkS")
		)
		(fp_line
			(start 2.1336 1.4224)
			(end 2.1336 -1.4224)
			(stroke
				(width 0.1524)
				(type default)
			)
			(layer "F.SilkS")
		)
		(fp_line
			(start -2.7432 1.4224)
			(end 2.1336 1.4224)
			(stroke
				(width 0.1524)
				(type default)
			)
			(layer "F.SilkS")
		)
		(fp_line
			(start -2.7432 1.4224)
			(end -2.6416 1.4224)
			(stroke
				(width 0.1524)
				(type default)
			)
			(layer "F.SilkS")
		)
		(fp_line
			(start -2.6289 3.4417)
			(end -2.6289 1.4732)
			(stroke
				(width 0.381)
				(type default)
			)
			(layer "F.SilkS")
		)
		(fp_poly
			(pts
				(xy -2.2098 -1.4224) (xy -2.2098 1.4224) (xy 2.2098 1.4224) (xy 2.2098 -1.4224)
			)
			(stroke
				(width 0)
				(type default)
			)
			(fill yes)
			(layer "F.SilkS")
		)
		(fp_rect
			(start -2.450084 2.999994)
			(end 2.450084 -2.999994)
			(stroke
				(width 0)
				(type default)
			)
			(fill no)
			(layer "F.CrtYd")
		)
		(fp_poly
			(pts
				(xy -2.8194 3.6322) (xy -2.8194 -3.6322) (xy 2.8194 -3.6322) (xy 2.8194 1.18364) (xy 2.450084 1.18364)
				(xy 2.450084 -2.999994) (xy -2.450084 -2.999994) (xy -2.450084 2.999994) (xy 2.450084 2.999994)
				(xy 2.450084 1.18618) (xy 2.8194 1.18618) (xy 2.8194 3.6322)
			)
			(stroke
				(width 0)
				(type default)
			)
			(fill no)
			(layer "F.CrtYd")
		)
		(fp_rect
			(start -2.8194 3.6322)
			(end 2.8194 -3.6322)
			(stroke
				(width 0)
				(type default)
			)
			(fill no)
			(layer "F.Fab")
		)
		(pad "1" smd rect
			(at -1.905 2.54 90)
			(size 0.635 1.651)
			(layers "F.Cu" "F.Mask" "F.Paste")
			(net "50M_CLK_OUT_R")
		)
		(pad "2" smd rect
			(at -0.635 2.54 90)
			(size 0.635 1.651)
			(layers "F.Cu" "F.Mask" "F.Paste")
			(net "CLK_50M_BMC_NCSI")
		)
		(pad "3" smd rect
			(at 0.635 2.54 90)
			(size 0.635 1.651)
			(layers "F.Cu" "F.Mask" "F.Paste")
			(net "CLK_50M_RMII_PHY")
		)
		(pad "4" smd rect
			(at 1.905 2.54 90)
			(size 0.635 1.651)
			(layers "F.Cu" "F.Mask" "F.Paste")
			(net "NCSI_10G_RCLK")
		)
		(pad "5" smd rect
			(at 1.905 -2.54 90)
			(size 0.635 1.651)
			(layers "F.Cu" "F.Mask" "F.Paste")
			(net "CLK_50M_BMC0")
		)
		(pad "6" smd rect
			(at 0.635 -2.54 90)
			(size 0.635 1.651)
			(layers "F.Cu" "F.Mask" "F.Paste")
			(net "GND")
		)
		(pad "7" smd rect
			(at -0.635 -2.54 90)
			(size 0.635 1.651)
			(layers "F.Cu" "F.Mask" "F.Paste")
			(net "P3V3_STBY")
		)
		(pad "8" smd rect
			(at -1.905 -2.54 90)
			(size 0.635 1.651)
			(layers "F.Cu" "F.Mask" "F.Paste")
			(net "50M_CLK_OE")
		)
	)
	(footprint ""
		(layer "F.Cu")
		(at 76.943966 -86.868 -90)
		(property "Reference" "SC1204"
			(at 0 0 270)
			(layer "F.SilkS")
			(hide yes)
			(effects
				(font
					(size 1.27 1.27)
				)
			)
		)
		(property "Value" "SC10U6D3V5KX-4GP"
			(at -0.0762 -6.1214 270)
			(unlocked yes)
			(layer "F.Fab")
			(hide yes)
			(effects
				(font
					(size 1.016 1.016)
					(thickness 0.1524)
				)
			)
		)
		(property "Device Type" "C805H58"
			(at -0.0762 -8.1534 270)
			(unlocked yes)
			(layer "F.Fab")
			(hide yes)
			(effects
				(font
					(size 1.016 1.016)
					(thickness 0.1524)
				)
			)
		)
		(duplicate_pad_numbers_are_jumpers no)
		(fp_line
			(start 0.635 0)
			(end -0.635 0)
			(stroke
				(width 0.508)
				(type default)
			)
			(layer "F.SilkS")
		)
		(fp_rect
			(start -0.9652 1.778)
			(end 0.9652 -1.778)
			(stroke
				(width 0)
				(type default)
			)
			(fill no)
			(layer "F.CrtYd")
		)
		(fp_poly
			(pts
				(xy -0.9652 -1.778) (xy 0.9652 -1.778) (xy 0.9652 1.778) (xy -0.9652 1.778)
			)
			(stroke
				(width 0)
				(type default)
			)
			(fill no)
			(layer "F.Fab")
		)
		(pad "1" smd rect
			(at 0 -0.9652 270)
			(size 1.397 1.143)
			(layers "F.Cu" "F.Mask" "F.Paste")
			(net "P1V8_E")
		)
		(pad "2" smd rect
			(at 0 0.9652 270)
			(size 1.397 1.143)
			(layers "F.Cu" "F.Mask" "F.Paste")
			(net "GND")
		)
	)
	(footprint ""
		(layer "F.Cu")
		(at 160.02 -147.066 -90)
		(property "Reference" "SR724"
			(at 0 0 270)
			(layer "F.SilkS")
			(hide yes)
			(effects
				(font
					(size 1.27 1.27)
				)
			)
		)
		(property "Value" "200KR2F-L-GP"
			(at 0.064008 -3.993896 270)
			(unlocked yes)
			(layer "F.Fab")
			(hide yes)
			(effects
				(font
					(size 1.016 1.016)
					(thickness 0.1524)
				)
			)
		)
		(property "Device Type" "R402H16"
			(at 0.064008 -5.517896 270)
			(unlocked yes)
			(layer "F.Fab")
			(hide yes)
			(effects
				(font
					(size 1.016 1.016)
					(thickness 0.1524)
				)
			)
		)
		(duplicate_pad_numbers_are_jumpers no)
		(fp_line
			(start -0.508 -0.9398)
			(end -0.508 0.9398)
			(stroke
				(width 0.1524)
				(type default)
			)
			(layer "F.SilkS")
		)
		(fp_line
			(start 0.508 -0.9398)
			(end -0.508 -0.9398)
			(stroke
				(width 0.1524)
				(type default)
			)
			(layer "F.SilkS")
		)
		(fp_rect
			(start -0.508 0.9398)
			(end 0.508 -0.9398)
			(stroke
				(width 0)
				(type default)
			)
			(fill no)
			(layer "F.CrtYd")
		)
		(fp_rect
			(start -0.508 0.9398)
			(end 0.508 -0.9398)
			(stroke
				(width 0)
				(type default)
			)
			(fill no)
			(layer "F.Fab")
		)
		(pad "1" smd custom
			(at 0 -0.4445 270)
			(size 0.1397 0.1397)
			(layers "F.Cu" "F.Mask" "F.Paste")
			(net "IOC_I2C_VREF")
			(options
				(clearance outline)
				(anchor circle)
			)
			(primitives
				(gr_poly
					(pts
						(arc
							(start -0.1778 -0.2794)
							(mid -0.249642 -0.249642)
							(end -0.2794 -0.1778)
						)
						(arc
							(start -0.2794 0.1778)
							(mid -0.249642 0.249642)
							(end -0.1778 0.2794)
						)
						(arc
							(start 0.1778 0.2794)
							(mid 0.249642 0.249642)
							(end 0.2794 0.1778)
						)
						(arc
							(start 0.2794 -0.1778)
							(mid 0.249642 -0.249642)
							(end 0.1778 -0.2794)
						)
					)
					(width 0)
					(fill yes)
				)
			)
		)
		(pad "2" smd custom
			(at 0 0.4445 270)
			(size 0.1397 0.1397)
			(layers "F.Cu" "F.Mask" "F.Paste")
			(net "P3V3")
			(options
				(clearance outline)
				(anchor circle)
			)
			(primitives
				(gr_poly
					(pts
						(arc
							(start -0.1778 -0.2794)
							(mid -0.249642 -0.249642)
							(end -0.2794 -0.1778)
						)
						(arc
							(start -0.2794 0.1778)
							(mid -0.249642 0.249642)
							(end -0.1778 0.2794)
						)
						(arc
							(start 0.1778 0.2794)
							(mid 0.249642 0.249642)
							(end 0.2794 0.1778)
						)
						(arc
							(start 0.2794 -0.1778)
							(mid 0.249642 -0.249642)
							(end 0.1778 -0.2794)
						)
					)
					(width 0)
					(fill yes)
				)
			)
		)
	)
)
